(kicad_pcb
	(version 20260206)
	(generator "pcbnew")
	(generator_version "10.0")
	(general
		(thickness 1.6)
		(legacy_teardrops no)
	)
	(paper "A4")
	(title_block
		(title "04192023_DAF0TMB3IC0_F0TG_MB_C_brd_V02_OCP.brd")
		(comment 1 "Grand Teton / footprints 8176-8182 of 8354")
	)
	(layers
		(0 "F.Cu" signal "TOP")
		(4 "In1.Cu" signal "GND")
		(6 "In2.Cu" signal "IN1")
		(8 "In3.Cu" signal "GND1")
		(10 "In4.Cu" signal "IN2")
		(12 "In5.Cu" signal "GND2")
		(14 "In6.Cu" signal "IN3")
		(16 "In7.Cu" signal "GND3")
		(18 "In8.Cu" signal "VCC")
		(20 "In9.Cu" signal "VCC1")
		(22 "In10.Cu" signal "GND4")
		(24 "In11.Cu" signal "IN4")
		(26 "In12.Cu" signal "GND5")
		(28 "In13.Cu" signal "IN5")
		(30 "In14.Cu" signal "GND6")
		(32 "In15.Cu" signal "IN6")
		(34 "In16.Cu" signal "GND7")
		(2 "B.Cu" signal "BOTTOM")
		(9 "F.Adhes" user "F.Adhesive")
		(11 "B.Adhes" user "B.Adhesive")
		(13 "F.Paste" user "Package Geometry/Pastemask Top")
		(15 "B.Paste" user "Package Geometry/Pastemask Bottom")
		(5 "F.SilkS" user "Ref Des/Silkscreen Top")
		(7 "B.SilkS" user "Ref Des/Silkscreen Bottom")
		(1 "F.Mask" user "Board Geometry/Soldermask Top")
		(3 "B.Mask" user "Board Geometry/Soldermask Bottom")
		(17 "Dwgs.User" user "User.Drawings")
		(19 "Cmts.User" user "User.Comments")
		(21 "Eco1.User" user "User.Eco1")
		(23 "Eco2.User" user "User.Eco2")
		(25 "Edge.Cuts" user "Board Geometry/Outline")
		(27 "Margin" user)
		(31 "F.CrtYd" user "Package Geometry/Place Bound Top")
		(29 "B.CrtYd" user "Package Geometry/Place Bound Bottom")
		(35 "F.Fab" user "Ref Des/Assembly Top")
		(33 "B.Fab" user "Ref Des/Assembly Bottom")
	)
	(footprint ""
		(layer "B.Cu")
		(at 111.476028 -256.012442 -90)
		(property "Reference" "C2473"
			(at 0 0 90)
			(layer "B.SilkS")
			(hide yes)
			(effects
				(font
					(size 1.27 1.27)
				)
				(justify mirror)
			)
		)
		(property "Value" ""
			(at 0 0 90)
			(layer "B.Fab")
			(effects
				(font
					(size 1.27 1.27)
				)
				(justify mirror)
			)
		)
		(duplicate_pad_numbers_are_jumpers no)
		(fp_line
			(start -0.7874 0.4064)
			(end 0.7874 0.4064)
			(stroke
				(width 0.1524)
				(type default)
			)
			(layer "B.SilkS")
		)
		(fp_line
			(start 0.7874 0.4064)
			(end 0.7874 -0.4064)
			(stroke
				(width 0.1524)
				(type default)
			)
			(layer "B.SilkS")
		)
		(fp_line
			(start -0.7874 -0.4064)
			(end -0.7874 0.4064)
			(stroke
				(width 0.1524)
				(type default)
			)
			(layer "B.SilkS")
		)
		(fp_line
			(start 0.7874 -0.4064)
			(end -0.7874 -0.4064)
			(stroke
				(width 0.1524)
				(type default)
			)
			(layer "B.SilkS")
		)
		(fp_line
			(start -0.67945 0.3048)
			(end -0.120396 0.3048)
			(stroke
				(width 0.1)
				(type default)
			)
			(layer "B.Fab")
		)
		(fp_line
			(start -0.120396 0.3048)
			(end -0.120396 0.2794)
			(stroke
				(width 0.1)
				(type default)
			)
			(layer "B.Fab")
		)
		(fp_line
			(start 0.12065 0.3048)
			(end 0.67945 0.3048)
			(stroke
				(width 0.1)
				(type default)
			)
			(layer "B.Fab")
		)
		(fp_line
			(start 0.67945 0.3048)
			(end 0.67945 -0.305054)
			(stroke
				(width 0.1)
				(type default)
			)
			(layer "B.Fab")
		)
		(fp_line
			(start -0.120396 0.2794)
			(end 0.12065 0.2794)
			(stroke
				(width 0.1)
				(type default)
			)
			(layer "B.Fab")
		)
		(fp_line
			(start 0.12065 0.2794)
			(end 0.12065 0.3048)
			(stroke
				(width 0.1)
				(type default)
			)
			(layer "B.Fab")
		)
		(fp_line
			(start -0.12065 -0.2794)
			(end -0.12065 -0.3048)
			(stroke
				(width 0.1)
				(type default)
			)
			(layer "B.Fab")
		)
		(fp_line
			(start 0.12065 -0.2794)
			(end -0.12065 -0.2794)
			(stroke
				(width 0.1)
				(type default)
			)
			(layer "B.Fab")
		)
		(fp_line
			(start -0.67945 -0.3048)
			(end -0.67945 0.3048)
			(stroke
				(width 0.1)
				(type default)
			)
			(layer "B.Fab")
		)
		(fp_line
			(start -0.12065 -0.3048)
			(end -0.67945 -0.3048)
			(stroke
				(width 0.1)
				(type default)
			)
			(layer "B.Fab")
		)
		(fp_line
			(start 0.12065 -0.305054)
			(end 0.12065 -0.2794)
			(stroke
				(width 0.1)
				(type default)
			)
			(layer "B.Fab")
		)
		(fp_line
			(start 0.67945 -0.305054)
			(end 0.12065 -0.305054)
			(stroke
				(width 0.1)
				(type default)
			)
			(layer "B.Fab")
		)
		(pad "1" smd circle
			(at 0.40005 0 90)
			(size 0 0)
			(layers "B.Cu" "B.Mask" "B.Paste")
			(net "PVDDCR_SOC_P1")
		)
		(pad "2" smd circle
			(at -0.40005 0 90)
			(size 0 0)
			(layers "B.Cu" "B.Mask" "B.Paste")
			(net "GND")
		)
	)
	(footprint ""
		(layer "B.Cu")
		(at 91.999054 -326.367902 -90)
		(property "Reference" "PC431_5"
			(at 0 0 90)
			(layer "B.SilkS")
			(hide yes)
			(effects
				(font
					(size 1.27 1.27)
				)
				(justify mirror)
			)
		)
		(property "Value" ""
			(at 0 0 90)
			(layer "B.Fab")
			(effects
				(font
					(size 1.27 1.27)
				)
				(justify mirror)
			)
		)
		(duplicate_pad_numbers_are_jumpers no)
		(fp_line
			(start -1.524 0.762)
			(end 1.524 0.762)
			(stroke
				(width 0.1524)
				(type default)
			)
			(layer "B.SilkS")
		)
		(fp_line
			(start 1.524 0.762)
			(end 1.524 -0.762)
			(stroke
				(width 0.1524)
				(type default)
			)
			(layer "B.SilkS")
		)
		(fp_line
			(start -1.524 -0.762)
			(end -1.524 0.762)
			(stroke
				(width 0.1524)
				(type default)
			)
			(layer "B.SilkS")
		)
		(fp_line
			(start 1.524 -0.762)
			(end -1.524 -0.762)
			(stroke
				(width 0.1524)
				(type default)
			)
			(layer "B.SilkS")
		)
		(fp_line
			(start -1.1049 0.724916)
			(end -1.1049 -0.724916)
			(stroke
				(width 0.1)
				(type default)
			)
			(layer "B.Fab")
		)
		(fp_line
			(start 1.1049 0.724916)
			(end -1.1049 0.724916)
			(stroke
				(width 0.1)
				(type default)
			)
			(layer "B.Fab")
		)
		(fp_line
			(start -1.1049 -0.724916)
			(end 1.1049 -0.724916)
			(stroke
				(width 0.1)
				(type default)
			)
			(layer "B.Fab")
		)
		(fp_line
			(start 1.1049 -0.724916)
			(end 1.1049 0.724916)
			(stroke
				(width 0.1)
				(type default)
			)
			(layer "B.Fab")
		)
		(pad "1" smd rect
			(at 0.889 0 270)
			(size 1.016 1.27)
			(layers "B.Cu" "B.Mask" "B.Paste")
			(net "PVDDCR_CPU1_P1")
		)
		(pad "2" smd rect
			(at -0.889 0 270)
			(size 1.016 1.27)
			(layers "B.Cu" "B.Mask" "B.Paste")
			(net "GND")
		)
	)
	(footprint ""
		(layer "B.Cu")
		(at 182.860696 -195.8594 180)
		(property "Reference" "R1708"
			(at 0 0 0)
			(layer "B.SilkS")
			(hide yes)
			(effects
				(font
					(size 1.27 1.27)
				)
				(justify mirror)
			)
		)
		(property "Value" ""
			(at 0 0 0)
			(layer "B.Fab")
			(effects
				(font
					(size 1.27 1.27)
				)
				(justify mirror)
			)
		)
		(duplicate_pad_numbers_are_jumpers no)
		(fp_line
			(start 0.7874 0.4064)
			(end 0.7874 -0.4064)
			(stroke
				(width 0.1524)
				(type default)
			)
			(layer "B.SilkS")
		)
		(fp_line
			(start 0.7874 -0.4064)
			(end -0.7874 -0.4064)
			(stroke
				(width 0.1524)
				(type default)
			)
			(layer "B.SilkS")
		)
		(fp_line
			(start -0.7874 0.4064)
			(end 0.7874 0.4064)
			(stroke
				(width 0.1524)
				(type default)
			)
			(layer "B.SilkS")
		)
		(fp_line
			(start -0.7874 -0.4064)
			(end -0.7874 0.4064)
			(stroke
				(width 0.1524)
				(type default)
			)
			(layer "B.SilkS")
		)
		(fp_line
			(start 0.67945 0.3048)
			(end 0.67945 -0.305054)
			(stroke
				(width 0.1)
				(type default)
			)
			(layer "B.Fab")
		)
		(fp_line
			(start 0.67945 -0.305054)
			(end 0.12065 -0.305054)
			(stroke
				(width 0.1)
				(type default)
			)
			(layer "B.Fab")
		)
		(fp_line
			(start 0.12065 0.3048)
			(end 0.67945 0.3048)
			(stroke
				(width 0.1)
				(type default)
			)
			(layer "B.Fab")
		)
		(fp_line
			(start 0.12065 0.2794)
			(end 0.12065 0.3048)
			(stroke
				(width 0.1)
				(type default)
			)
			(layer "B.Fab")
		)
		(fp_line
			(start 0.12065 -0.2794)
			(end -0.12065 -0.2794)
			(stroke
				(width 0.1)
				(type default)
			)
			(layer "B.Fab")
		)
		(fp_line
			(start 0.12065 -0.305054)
			(end 0.12065 -0.2794)
			(stroke
				(width 0.1)
				(type default)
			)
			(layer "B.Fab")
		)
		(fp_line
			(start -0.120396 0.3048)
			(end -0.120396 0.2794)
			(stroke
				(width 0.1)
				(type default)
			)
			(layer "B.Fab")
		)
		(fp_line
			(start -0.120396 0.2794)
			(end 0.12065 0.2794)
			(stroke
				(width 0.1)
				(type default)
			)
			(layer "B.Fab")
		)
		(fp_line
			(start -0.12065 -0.2794)
			(end -0.12065 -0.3048)
			(stroke
				(width 0.1)
				(type default)
			)
			(layer "B.Fab")
		)
		(fp_line
			(start -0.12065 -0.3048)
			(end -0.67945 -0.3048)
			(stroke
				(width 0.1)
				(type default)
			)
			(layer "B.Fab")
		)
		(fp_line
			(start -0.67945 0.3048)
			(end -0.120396 0.3048)
			(stroke
				(width 0.1)
				(type default)
			)
			(layer "B.Fab")
		)
		(fp_line
			(start -0.67945 -0.3048)
			(end -0.67945 0.3048)
			(stroke
				(width 0.1)
				(type default)
			)
			(layer "B.Fab")
		)
		(pad "1" smd circle
			(at 0.40005 0)
			(size 0 0)
			(layers "B.Cu" "B.Mask" "B.Paste")
			(net "I3C_SPD_DDRGL_CPU1_SDA")
		)
		(pad "2" smd circle
			(at -0.40005 0)
			(size 0 0)
			(layers "B.Cu" "B.Mask" "B.Paste")
			(net "I3C_SPD_DDRI_CPU1_SDA")
		)
	)
	(footprint ""
		(layer "B.Cu")
		(at 123.357386 -264.354564)
		(property "Reference" "C2483"
			(at 0 0 0)
			(layer "B.SilkS")
			(hide yes)
			(effects
				(font
					(size 1.27 1.27)
				)
				(justify mirror)
			)
		)
		(property "Value" ""
			(at 0 0 0)
			(layer "B.Fab")
			(effects
				(font
					(size 1.27 1.27)
				)
				(justify mirror)
			)
		)
		(duplicate_pad_numbers_are_jumpers no)
		(fp_line
			(start -0.7874 -0.4064)
			(end -0.7874 0.4064)
			(stroke
				(width 0.1524)
				(type default)
			)
			(layer "B.SilkS")
		)
		(fp_line
			(start -0.7874 0.4064)
			(end 0.7874 0.4064)
			(stroke
				(width 0.1524)
				(type default)
			)
			(layer "B.SilkS")
		)
		(fp_line
			(start 0.7874 -0.4064)
			(end -0.7874 -0.4064)
			(stroke
				(width 0.1524)
				(type default)
			)
			(layer "B.SilkS")
		)
		(fp_line
			(start 0.7874 0.4064)
			(end 0.7874 -0.4064)
			(stroke
				(width 0.1524)
				(type default)
			)
			(layer "B.SilkS")
		)
		(fp_line
			(start -0.67945 -0.3048)
			(end -0.67945 0.3048)
			(stroke
				(width 0.1)
				(type default)
			)
			(layer "B.Fab")
		)
		(fp_line
			(start -0.67945 0.3048)
			(end -0.120396 0.3048)
			(stroke
				(width 0.1)
				(type default)
			)
			(layer "B.Fab")
		)
		(fp_line
			(start -0.12065 -0.3048)
			(end -0.67945 -0.3048)
			(stroke
				(width 0.1)
				(type default)
			)
			(layer "B.Fab")
		)
		(fp_line
			(start -0.12065 -0.2794)
			(end -0.12065 -0.3048)
			(stroke
				(width 0.1)
				(type default)
			)
			(layer "B.Fab")
		)
		(fp_line
			(start -0.120396 0.2794)
			(end 0.12065 0.2794)
			(stroke
				(width 0.1)
				(type default)
			)
			(layer "B.Fab")
		)
		(fp_line
			(start -0.120396 0.3048)
			(end -0.120396 0.2794)
			(stroke
				(width 0.1)
				(type default)
			)
			(layer "B.Fab")
		)
		(fp_line
			(start 0.12065 -0.305054)
			(end 0.12065 -0.2794)
			(stroke
				(width 0.1)
				(type default)
			)
			(layer "B.Fab")
		)
		(fp_line
			(start 0.12065 -0.2794)
			(end -0.12065 -0.2794)
			(stroke
				(width 0.1)
				(type default)
			)
			(layer "B.Fab")
		)
		(fp_line
			(start 0.12065 0.2794)
			(end 0.12065 0.3048)
			(stroke
				(width 0.1)
				(type default)
			)
			(layer "B.Fab")
		)
		(fp_line
			(start 0.12065 0.3048)
			(end 0.67945 0.3048)
			(stroke
				(width 0.1)
				(type default)
			)
			(layer "B.Fab")
		)
		(fp_line
			(start 0.67945 -0.305054)
			(end 0.12065 -0.305054)
			(stroke
				(width 0.1)
				(type default)
			)
			(layer "B.Fab")
		)
		(fp_line
			(start 0.67945 0.3048)
			(end 0.67945 -0.305054)
			(stroke
				(width 0.1)
				(type default)
			)
			(layer "B.Fab")
		)
		(pad "1" smd circle
			(at 0.40005 0 180)
			(size 0 0)
			(layers "B.Cu" "B.Mask" "B.Paste")
			(net "PVDD11_S3_P1")
		)
		(pad "2" smd circle
			(at -0.40005 0 180)
			(size 0 0)
			(layers "B.Cu" "B.Mask" "B.Paste")
			(net "GND")
		)
	)
	(footprint ""
		(layer "B.Cu")
		(at 319.118234 -396.393162 -90)
		(property "Reference" "C582"
			(at 0 0 90)
			(layer "B.SilkS")
			(hide yes)
			(effects
				(font
					(size 1.27 1.27)
				)
				(justify mirror)
			)
		)
		(property "Value" ""
			(at 0 0 90)
			(layer "B.Fab")
			(effects
				(font
					(size 1.27 1.27)
				)
				(justify mirror)
			)
		)
		(duplicate_pad_numbers_are_jumpers no)
		(fp_line
			(start -0.299974 0.150114)
			(end 0.299974 0.150114)
			(stroke
				(width 0.1)
				(type default)
			)
			(layer "B.Fab")
		)
		(fp_line
			(start 0.299974 0.150114)
			(end 0.299974 -0.150114)
			(stroke
				(width 0.1)
				(type default)
			)
			(layer "B.Fab")
		)
		(fp_line
			(start -0.299974 -0.150114)
			(end -0.299974 0.150114)
			(stroke
				(width 0.1)
				(type default)
			)
			(layer "B.Fab")
		)
		(fp_line
			(start 0.299974 -0.150114)
			(end -0.299974 -0.150114)
			(stroke
				(width 0.1)
				(type default)
			)
			(layer "B.Fab")
		)
		(pad "1" smd rect
			(at 0.2667 0 90)
			(size 0.3048 0.381)
			(layers "B.Cu" "B.Mask" "B.Paste")
			(net "P0V9_CPU0_RT0_2A")
		)
		(pad "2" smd rect
			(at -0.2667 0 90)
			(size 0.3048 0.381)
			(layers "B.Cu" "B.Mask" "B.Paste")
			(net "GND")
		)
	)
	(footprint ""
		(layer "B.Cu")
		(at 240.411 -231.648 -90)
		(property "Reference" "R370"
			(at 0 0 90)
			(layer "B.SilkS")
			(hide yes)
			(effects
				(font
					(size 1.27 1.27)
				)
				(justify mirror)
			)
		)
		(property "Value" ""
			(at 0 0 90)
			(layer "B.Fab")
			(effects
				(font
					(size 1.27 1.27)
				)
				(justify mirror)
			)
		)
		(duplicate_pad_numbers_are_jumpers no)
		(fp_line
			(start -0.7874 0.4064)
			(end 0.7874 0.4064)
			(stroke
				(width 0.1524)
				(type default)
			)
			(layer "B.SilkS")
		)
		(fp_line
			(start 0.7874 0.4064)
			(end 0.7874 -0.4064)
			(stroke
				(width 0.1524)
				(type default)
			)
			(layer "B.SilkS")
		)
		(fp_line
			(start -0.7874 -0.4064)
			(end -0.7874 0.4064)
			(stroke
				(width 0.1524)
				(type default)
			)
			(layer "B.SilkS")
		)
		(fp_line
			(start 0.7874 -0.4064)
			(end -0.7874 -0.4064)
			(stroke
				(width 0.1524)
				(type default)
			)
			(layer "B.SilkS")
		)
		(fp_line
			(start -0.67945 0.3048)
			(end -0.120396 0.3048)
			(stroke
				(width 0.1)
				(type default)
			)
			(layer "B.Fab")
		)
		(fp_line
			(start -0.120396 0.3048)
			(end -0.120396 0.2794)
			(stroke
				(width 0.1)
				(type default)
			)
			(layer "B.Fab")
		)
		(fp_line
			(start 0.12065 0.3048)
			(end 0.67945 0.3048)
			(stroke
				(width 0.1)
				(type default)
			)
			(layer "B.Fab")
		)
		(fp_line
			(start 0.67945 0.3048)
			(end 0.67945 -0.305054)
			(stroke
				(width 0.1)
				(type default)
			)
			(layer "B.Fab")
		)
		(fp_line
			(start -0.120396 0.2794)
			(end 0.12065 0.2794)
			(stroke
				(width 0.1)
				(type default)
			)
			(layer "B.Fab")
		)
		(fp_line
			(start 0.12065 0.2794)
			(end 0.12065 0.3048)
			(stroke
				(width 0.1)
				(type default)
			)
			(layer "B.Fab")
		)
		(fp_line
			(start -0.12065 -0.2794)
			(end -0.12065 -0.3048)
			(stroke
				(width 0.1)
				(type default)
			)
			(layer "B.Fab")
		)
		(fp_line
			(start 0.12065 -0.2794)
			(end -0.12065 -0.2794)
			(stroke
				(width 0.1)
				(type default)
			)
			(layer "B.Fab")
		)
		(fp_line
			(start -0.67945 -0.3048)
			(end -0.67945 0.3048)
			(stroke
				(width 0.1)
				(type default)
			)
			(layer "B.Fab")
		)
		(fp_line
			(start -0.12065 -0.3048)
			(end -0.67945 -0.3048)
			(stroke
				(width 0.1)
				(type default)
			)
			(layer "B.Fab")
		)
		(fp_line
			(start 0.12065 -0.305054)
			(end 0.12065 -0.2794)
			(stroke
				(width 0.1)
				(type default)
			)
			(layer "B.Fab")
		)
		(fp_line
			(start 0.67945 -0.305054)
			(end 0.12065 -0.305054)
			(stroke
				(width 0.1)
				(type default)
			)
			(layer "B.Fab")
		)
		(pad "1" smd circle
			(at 0.40005 0 90)
			(size 0 0)
			(layers "B.Cu" "B.Mask" "B.Paste")
			(net "PVDD18_S5_P0")
		)
		(pad "2" smd circle
			(at -0.40005 0 90)
			(size 0 0)
			(layers "B.Cu" "B.Mask" "B.Paste")
			(net "SMB_CPU0_SEC_SDA")
		)
	)
	(footprint ""
		(layer "B.Cu")
		(at 94.059502 -205.14945 90)
		(property "Reference" "R533"
			(at 0 0 90)
			(layer "B.SilkS")
			(hide yes)
			(effects
				(font
					(size 1.27 1.27)
				)
				(justify mirror)
			)
		)
		(property "Value" ""
			(at 0 0 90)
			(layer "B.Fab")
			(effects
				(font
					(size 1.27 1.27)
				)
				(justify mirror)
			)
		)
		(duplicate_pad_numbers_are_jumpers no)
		(fp_line
			(start 0.7874 -0.4064)
			(end -0.7874 -0.4064)
			(stroke
				(width 0.1524)
				(type default)
			)
			(layer "B.SilkS")
		)
		(fp_line
			(start -0.7874 -0.4064)
			(end -0.7874 0.4064)
			(stroke
				(width 0.1524)
				(type default)
			)
			(layer "B.SilkS")
		)
		(fp_line
			(start 0.7874 0.4064)
			(end 0.7874 -0.4064)
			(stroke
				(width 0.1524)
				(type default)
			)
			(layer "B.SilkS")
		)
		(fp_line
			(start -0.7874 0.4064)
			(end 0.7874 0.4064)
			(stroke
				(width 0.1524)
				(type default)
			)
			(layer "B.SilkS")
		)
		(fp_line
			(start 0.67945 -0.305054)
			(end 0.12065 -0.305054)
			(stroke
				(width 0.1)
				(type default)
			)
			(layer "B.Fab")
		)
		(fp_line
			(start 0.12065 -0.305054)
			(end 0.12065 -0.2794)
			(stroke
				(width 0.1)
				(type default)
			)
			(layer "B.Fab")
		)
		(fp_line
			(start -0.12065 -0.3048)
			(end -0.67945 -0.3048)
			(stroke
				(width 0.1)
				(type default)
			)
			(layer "B.Fab")
		)
		(fp_line
			(start -0.67945 -0.3048)
			(end -0.67945 0.3048)
			(stroke
				(width 0.1)
				(type default)
			)
			(layer "B.Fab")
		)
		(fp_line
			(start 0.12065 -0.2794)
			(end -0.12065 -0.2794)
			(stroke
				(width 0.1)
				(type default)
			)
			(layer "B.Fab")
		)
		(fp_line
			(start -0.12065 -0.2794)
			(end -0.12065 -0.3048)
			(stroke
				(width 0.1)
				(type default)
			)
			(layer "B.Fab")
		)
		(fp_line
			(start 0.12065 0.2794)
			(end 0.12065 0.3048)
			(stroke
				(width 0.1)
				(type default)
			)
			(layer "B.Fab")
		)
		(fp_line
			(start -0.120396 0.2794)
			(end 0.12065 0.2794)
			(stroke
				(width 0.1)
				(type default)
			)
			(layer "B.Fab")
		)
		(fp_line
			(start 0.67945 0.3048)
			(end 0.67945 -0.305054)
			(stroke
				(width 0.1)
				(type default)
			)
			(layer "B.Fab")
		)
		(fp_line
			(start 0.12065 0.3048)
			(end 0.67945 0.3048)
			(stroke
				(width 0.1)
				(type default)
			)
			(layer "B.Fab")
		)
		(fp_line
			(start -0.120396 0.3048)
			(end -0.120396 0.2794)
			(stroke
				(width 0.1)
				(type default)
			)
			(layer "B.Fab")
		)
		(fp_line
			(start -0.67945 0.3048)
			(end -0.120396 0.3048)
			(stroke
				(width 0.1)
				(type default)
			)
			(layer "B.Fab")
		)
		(pad "1" smd circle
			(at 0.40005 0 270)
			(size 0 0)
			(layers "B.Cu" "B.Mask" "B.Paste")
			(net "CPU1_BP2")
		)
		(pad "2" smd circle
			(at -0.40005 0 270)
			(size 0 0)
			(layers "B.Cu" "B.Mask" "B.Paste")
			(net "PVDD18_S5_P1")
		)
	)
)
